(kicad_pcb
	(version 20260206)
	(generator "pcbnew")
	(generator_version "10.0")
	(general
		(thickness 1.6)
		(legacy_teardrops no)
	)
	(paper "A4")
	(title_block
		(title "fcb — Lightning_FCB_BRD.brd")
		(comment 1 "Lightning (Wiwynn / Facebook NVMe JBOF) / footprints 336-342 of 495")
	)
	(layers
		(0 "F.Cu" signal "TOP")
		(4 "In1.Cu" signal "L2GND")
		(6 "In2.Cu" signal "L3VCC")
		(2 "B.Cu" signal "BOTTOM")
		(9 "F.Adhes" user "F.Adhesive")
		(11 "B.Adhes" user "B.Adhesive")
		(13 "F.Paste" user "Package Geometry/Pastemask Top")
		(15 "B.Paste" user "Package Geometry/Pastemask Bottom")
		(5 "F.SilkS" user "Ref Des/Silkscreen Top")
		(7 "B.SilkS" user "Ref Des/Silkscreen Bottom")
		(1 "F.Mask" user "Board Geometry/Soldermask Top")
		(3 "B.Mask" user "Board Geometry/Soldermask Bottom")
		(17 "Dwgs.User" user "User.Drawings")
		(19 "Cmts.User" user "User.Comments")
		(21 "Eco1.User" user "User.Eco1")
		(23 "Eco2.User" user "User.Eco2")
		(25 "Edge.Cuts" user "Board Geometry/Outline")
		(27 "Margin" user)
		(31 "F.CrtYd" user "Package Geometry/Place Bound Top")
		(29 "B.CrtYd" user "Package Geometry/Place Bound Bottom")
		(35 "F.Fab" user "Ref Des/Assembly Top")
		(33 "B.Fab" user "Ref Des/Assembly Bottom")
	)
	(footprint ""
		(layer "F.Cu")
		(at 28.2956 -362.1786 90)
		(property "Reference" "PR12"
			(at 0 0 90)
			(layer "F.SilkS")
			(hide yes)
			(effects
				(font
					(size 1.27 1.27)
				)
			)
		)
		(property "Value" "0R2J-2-GP"
			(at 0.064008 -3.993896 90)
			(unlocked yes)
			(layer "F.Fab")
			(hide yes)
			(effects
				(font
					(size 1.016 1.016)
					(thickness 0.1524)
				)
			)
		)
		(property "Device Type" "R402H16"
			(at 0.064008 -5.517896 90)
			(unlocked yes)
			(layer "F.Fab")
			(hide yes)
			(effects
				(font
					(size 1.016 1.016)
					(thickness 0.1524)
				)
			)
		)
		(duplicate_pad_numbers_are_jumpers no)
		(fp_line
			(start 0.508 -0.9398)
			(end -0.508 -0.9398)
			(stroke
				(width 0.1524)
				(type default)
			)
			(layer "F.SilkS")
		)
		(fp_line
			(start -0.508 -0.9398)
			(end -0.508 0.9398)
			(stroke
				(width 0.1524)
				(type default)
			)
			(layer "F.SilkS")
		)
		(fp_rect
			(start -0.508 0.9398)
			(end 0.508 -0.9398)
			(stroke
				(width 0)
				(type default)
			)
			(fill no)
			(layer "F.CrtYd")
		)
		(fp_rect
			(start -0.508 0.9398)
			(end 0.508 -0.9398)
			(stroke
				(width 0)
				(type default)
			)
			(fill no)
			(layer "F.Fab")
		)
		(pad "1" smd custom
			(at 0 -0.4445 90)
			(size 0.1397 0.1397)
			(layers "F.Cu" "F.Mask" "F.Paste")
			(net "ADM1276_LATCH#")
			(options
				(clearance outline)
				(anchor circle)
			)
			(primitives
				(gr_poly
					(pts
						(arc
							(start -0.1778 -0.2794)
							(mid -0.249642 -0.249642)
							(end -0.2794 -0.1778)
						)
						(arc
							(start -0.2794 0.1778)
							(mid -0.249642 0.249642)
							(end -0.1778 0.2794)
						)
						(arc
							(start 0.1778 0.2794)
							(mid 0.249642 0.249642)
							(end 0.2794 0.1778)
						)
						(arc
							(start 0.2794 -0.1778)
							(mid 0.249642 -0.249642)
							(end 0.1778 -0.2794)
						)
					)
					(width 0)
					(fill yes)
				)
			)
		)
		(pad "2" smd custom
			(at 0 0.4445 90)
			(size 0.1397 0.1397)
			(layers "F.Cu" "F.Mask" "F.Paste")
			(net "ADM1276_EN")
			(options
				(clearance outline)
				(anchor circle)
			)
			(primitives
				(gr_poly
					(pts
						(arc
							(start -0.1778 -0.2794)
							(mid -0.249642 -0.249642)
							(end -0.2794 -0.1778)
						)
						(arc
							(start -0.2794 0.1778)
							(mid -0.249642 0.249642)
							(end -0.1778 0.2794)
						)
						(arc
							(start 0.1778 0.2794)
							(mid 0.249642 0.249642)
							(end 0.2794 0.1778)
						)
						(arc
							(start 0.2794 -0.1778)
							(mid 0.249642 -0.249642)
							(end 0.1778 -0.2794)
						)
					)
					(width 0)
					(fill yes)
				)
			)
		)
	)
	(footprint ""
		(layer "F.Cu")
		(at 26.3906 -121.7676)
		(property "Reference" "C258"
			(at 0 0 0)
			(layer "F.SilkS")
			(hide yes)
			(effects
				(font
					(size 1.27 1.27)
				)
			)
		)
		(property "Value" "SC1U25V3KX-1-GP"
			(at 0 -2.8194 0)
			(unlocked yes)
			(layer "F.Fab")
			(hide yes)
			(effects
				(font
					(size 1.016 1.016)
					(thickness 0.1524)
				)
			)
		)
		(property "Device Type" "C603H36"
			(at 0 -4.3434 0)
			(unlocked yes)
			(layer "F.Fab")
			(hide yes)
			(effects
				(font
					(size 1.016 1.016)
					(thickness 0.1524)
				)
			)
		)
		(duplicate_pad_numbers_are_jumpers no)
		(fp_line
			(start 0.508 0)
			(end -0.508 0)
			(stroke
				(width 0.2032)
				(type default)
			)
			(layer "F.SilkS")
		)
		(fp_rect
			(start -0.5842 1.3335)
			(end 0.5842 -1.3335)
			(stroke
				(width 0)
				(type default)
			)
			(fill no)
			(layer "F.CrtYd")
		)
		(fp_rect
			(start -0.5842 1.3335)
			(end 0.5842 -1.3335)
			(stroke
				(width 0)
				(type default)
			)
			(fill no)
			(layer "F.Fab")
		)
		(pad "1" smd custom
			(at 0 -0.762)
			(size 0.2159 0.2159)
			(layers "F.Cu" "F.Mask" "F.Paste")
			(net "P12V")
			(options
				(clearance outline)
				(anchor circle)
			)
			(primitives
				(gr_poly
					(pts
						(arc
							(start -0.3302 -0.4318)
							(mid -0.402042 -0.402042)
							(end -0.4318 -0.3302)
						)
						(arc
							(start -0.4318 0.3302)
							(mid -0.402042 0.402042)
							(end -0.3302 0.4318)
						)
						(arc
							(start 0.3302 0.4318)
							(mid 0.402042 0.402042)
							(end 0.4318 0.3302)
						)
						(arc
							(start 0.4318 -0.3302)
							(mid 0.402042 -0.402042)
							(end 0.3302 -0.4318)
						)
					)
					(width 0)
					(fill yes)
				)
			)
		)
		(pad "2" smd custom
			(at 0 0.762)
			(size 0.2159 0.2159)
			(layers "F.Cu" "F.Mask" "F.Paste")
			(net "GND")
			(options
				(clearance outline)
				(anchor circle)
			)
			(primitives
				(gr_poly
					(pts
						(arc
							(start -0.3302 -0.4318)
							(mid -0.402042 -0.402042)
							(end -0.4318 -0.3302)
						)
						(arc
							(start -0.4318 0.3302)
							(mid -0.402042 0.402042)
							(end -0.3302 0.4318)
						)
						(arc
							(start 0.3302 0.4318)
							(mid 0.402042 0.402042)
							(end 0.4318 0.3302)
						)
						(arc
							(start 0.4318 -0.3302)
							(mid 0.402042 -0.402042)
							(end 0.3302 -0.4318)
						)
					)
					(width 0)
					(fill yes)
				)
			)
		)
	)
	(footprint ""
		(layer "F.Cu")
		(at 45.81271 -163.594034)
		(property "Reference" "R3"
			(at 0 0 0)
			(layer "F.SilkS")
			(hide yes)
			(effects
				(font
					(size 1.27 1.27)
				)
			)
		)
		(property "Value" "4K7R2F-GP"
			(at 0.064008 -3.993896 0)
			(unlocked yes)
			(layer "F.Fab")
			(hide yes)
			(effects
				(font
					(size 1.016 1.016)
					(thickness 0.1524)
				)
			)
		)
		(property "Device Type" "R402H16"
			(at 0.064008 -5.517896 0)
			(unlocked yes)
			(layer "F.Fab")
			(hide yes)
			(effects
				(font
					(size 1.016 1.016)
					(thickness 0.1524)
				)
			)
		)
		(duplicate_pad_numbers_are_jumpers no)
		(fp_line
			(start -0.508 -0.9398)
			(end -0.508 0.9398)
			(stroke
				(width 0.1524)
				(type default)
			)
			(layer "F.SilkS")
		)
		(fp_line
			(start 0.508 -0.9398)
			(end -0.508 -0.9398)
			(stroke
				(width 0.1524)
				(type default)
			)
			(layer "F.SilkS")
		)
		(fp_rect
			(start -0.508 0.9398)
			(end 0.508 -0.9398)
			(stroke
				(width 0)
				(type default)
			)
			(fill no)
			(layer "F.CrtYd")
		)
		(fp_rect
			(start -0.508 0.9398)
			(end 0.508 -0.9398)
			(stroke
				(width 0)
				(type default)
			)
			(fill no)
			(layer "F.Fab")
		)
		(pad "1" smd custom
			(at 0 -0.4445)
			(size 0.1397 0.1397)
			(layers "F.Cu" "F.Mask" "F.Paste")
			(net "OSC_TRI_S")
			(options
				(clearance outline)
				(anchor circle)
			)
			(primitives
				(gr_poly
					(pts
						(arc
							(start -0.1778 -0.2794)
							(mid -0.249642 -0.249642)
							(end -0.2794 -0.1778)
						)
						(arc
							(start -0.2794 0.1778)
							(mid -0.249642 0.249642)
							(end -0.1778 0.2794)
						)
						(arc
							(start 0.1778 0.2794)
							(mid 0.249642 0.249642)
							(end 0.2794 0.1778)
						)
						(arc
							(start 0.2794 -0.1778)
							(mid 0.249642 -0.249642)
							(end 0.1778 -0.2794)
						)
					)
					(width 0)
					(fill yes)
				)
			)
		)
		(pad "2" smd custom
			(at 0 0.4445)
			(size 0.1397 0.1397)
			(layers "F.Cu" "F.Mask" "F.Paste")
			(net "P3V3")
			(options
				(clearance outline)
				(anchor circle)
			)
			(primitives
				(gr_poly
					(pts
						(arc
							(start -0.1778 -0.2794)
							(mid -0.249642 -0.249642)
							(end -0.2794 -0.1778)
						)
						(arc
							(start -0.2794 0.1778)
							(mid -0.249642 0.249642)
							(end -0.1778 0.2794)
						)
						(arc
							(start 0.1778 0.2794)
							(mid 0.249642 0.249642)
							(end 0.2794 0.1778)
						)
						(arc
							(start 0.2794 -0.1778)
							(mid 0.249642 -0.249642)
							(end 0.1778 -0.2794)
						)
					)
					(width 0)
					(fill yes)
				)
			)
		)
	)
	(footprint ""
		(layer "F.Cu")
		(at 31.75 -381 180)
		(property "Reference" "PR21"
			(at 0 0 180)
			(layer "F.SilkS")
			(hide yes)
			(effects
				(font
					(size 1.27 1.27)
				)
			)
		)
		(property "Value" "10R2F-L-GP"
			(at 0.064008 -3.993896 180)
			(unlocked yes)
			(layer "F.Fab")
			(hide yes)
			(effects
				(font
					(size 1.016 1.016)
					(thickness 0.1524)
				)
			)
		)
		(property "Device Type" "R402H14"
			(at 0.064008 -5.517896 180)
			(unlocked yes)
			(layer "F.Fab")
			(hide yes)
			(effects
				(font
					(size 1.016 1.016)
					(thickness 0.1524)
				)
			)
		)
		(duplicate_pad_numbers_are_jumpers no)
		(fp_line
			(start 0.508 -0.9398)
			(end -0.508 -0.9398)
			(stroke
				(width 0.1524)
				(type default)
			)
			(layer "F.SilkS")
		)
		(fp_line
			(start -0.508 -0.9398)
			(end -0.508 0.9398)
			(stroke
				(width 0.1524)
				(type default)
			)
			(layer "F.SilkS")
		)
		(fp_rect
			(start -0.508 0.9398)
			(end 0.508 -0.9398)
			(stroke
				(width 0)
				(type default)
			)
			(fill no)
			(layer "F.CrtYd")
		)
		(fp_rect
			(start -0.508 0.9398)
			(end 0.508 -0.9398)
			(stroke
				(width 0)
				(type default)
			)
			(fill no)
			(layer "F.Fab")
		)
		(pad "1" smd custom
			(at 0 -0.4445 180)
			(size 0.1397 0.1397)
			(layers "F.Cu" "F.Mask" "F.Paste")
			(net "ADM1276_SENSE-")
			(options
				(clearance outline)
				(anchor circle)
			)
			(primitives
				(gr_poly
					(pts
						(arc
							(start -0.1778 -0.2794)
							(mid -0.249642 -0.249642)
							(end -0.2794 -0.1778)
						)
						(arc
							(start -0.2794 0.1778)
							(mid -0.249642 0.249642)
							(end -0.1778 0.2794)
						)
						(arc
							(start 0.1778 0.2794)
							(mid 0.249642 0.249642)
							(end 0.2794 0.1778)
						)
						(arc
							(start 0.2794 -0.1778)
							(mid 0.249642 -0.249642)
							(end 0.1778 -0.2794)
						)
					)
					(width 0)
					(fill yes)
				)
			)
		)
		(pad "2" smd custom
			(at 0 0.4445 180)
			(size 0.1397 0.1397)
			(layers "F.Cu" "F.Mask" "F.Paste")
			(net "SENSE-_R1")
			(options
				(clearance outline)
				(anchor circle)
			)
			(primitives
				(gr_poly
					(pts
						(arc
							(start -0.1778 -0.2794)
							(mid -0.249642 -0.249642)
							(end -0.2794 -0.1778)
						)
						(arc
							(start -0.2794 0.1778)
							(mid -0.249642 0.249642)
							(end -0.1778 0.2794)
						)
						(arc
							(start 0.1778 0.2794)
							(mid 0.249642 0.249642)
							(end 0.2794 0.1778)
						)
						(arc
							(start 0.2794 -0.1778)
							(mid 0.249642 -0.249642)
							(end 0.1778 -0.2794)
						)
					)
					(width 0)
					(fill yes)
				)
			)
		)
	)
	(footprint ""
		(layer "F.Cu")
		(at 15.6464 -53.2384 180)
		(property "Reference" "R357"
			(at 0 0 180)
			(layer "F.SilkS")
			(hide yes)
			(effects
				(font
					(size 1.27 1.27)
				)
			)
		)
		(property "Value" "10KR2F-2-GP"
			(at 0.064008 -3.993896 180)
			(unlocked yes)
			(layer "F.Fab")
			(hide yes)
			(effects
				(font
					(size 1.016 1.016)
					(thickness 0.1524)
				)
			)
		)
		(property "Device Type" "R402H16"
			(at 0.064008 -5.517896 180)
			(unlocked yes)
			(layer "F.Fab")
			(hide yes)
			(effects
				(font
					(size 1.016 1.016)
					(thickness 0.1524)
				)
			)
		)
		(duplicate_pad_numbers_are_jumpers no)
		(fp_line
			(start 0.508 -0.9398)
			(end -0.508 -0.9398)
			(stroke
				(width 0.1524)
				(type default)
			)
			(layer "F.SilkS")
		)
		(fp_line
			(start -0.508 -0.9398)
			(end -0.508 0.9398)
			(stroke
				(width 0.1524)
				(type default)
			)
			(layer "F.SilkS")
		)
		(fp_rect
			(start -0.508 0.9398)
			(end 0.508 -0.9398)
			(stroke
				(width 0)
				(type default)
			)
			(fill no)
			(layer "F.CrtYd")
		)
		(fp_rect
			(start -0.508 0.9398)
			(end 0.508 -0.9398)
			(stroke
				(width 0)
				(type default)
			)
			(fill no)
			(layer "F.Fab")
		)
		(pad "1" smd custom
			(at 0 -0.4445 180)
			(size 0.1397 0.1397)
			(layers "F.Cu" "F.Mask" "F.Paste")
			(net "P3V3")
			(options
				(clearance outline)
				(anchor circle)
			)
			(primitives
				(gr_poly
					(pts
						(arc
							(start -0.1778 -0.2794)
							(mid -0.249642 -0.249642)
							(end -0.2794 -0.1778)
						)
						(arc
							(start -0.2794 0.1778)
							(mid -0.249642 0.249642)
							(end -0.1778 0.2794)
						)
						(arc
							(start 0.1778 0.2794)
							(mid 0.249642 0.249642)
							(end 0.2794 0.1778)
						)
						(arc
							(start 0.2794 -0.1778)
							(mid 0.249642 -0.249642)
							(end 0.1778 -0.2794)
						)
					)
					(width 0)
					(fill yes)
				)
			)
		)
		(pad "2" smd custom
			(at 0 0.4445 180)
			(size 0.1397 0.1397)
			(layers "F.Cu" "F.Mask" "F.Paste")
			(net "FCB_HW_REVISION")
			(options
				(clearance outline)
				(anchor circle)
			)
			(primitives
				(gr_poly
					(pts
						(arc
							(start -0.1778 -0.2794)
							(mid -0.249642 -0.249642)
							(end -0.2794 -0.1778)
						)
						(arc
							(start -0.2794 0.1778)
							(mid -0.249642 0.249642)
							(end -0.1778 0.2794)
						)
						(arc
							(start 0.1778 0.2794)
							(mid 0.249642 0.249642)
							(end 0.2794 0.1778)
						)
						(arc
							(start 0.2794 -0.1778)
							(mid 0.249642 -0.249642)
							(end 0.1778 -0.2794)
						)
					)
					(width 0)
					(fill yes)
				)
			)
		)
	)
	(footprint ""
		(layer "F.Cu")
		(at 27.686 -381 180)
		(property "Reference" "PR17"
			(at 0 0 180)
			(layer "F.SilkS")
			(hide yes)
			(effects
				(font
					(size 1.27 1.27)
				)
			)
		)
		(property "Value" "10R2F-L-GP"
			(at 0.064008 -3.993896 180)
			(unlocked yes)
			(layer "F.Fab")
			(hide yes)
			(effects
				(font
					(size 1.016 1.016)
					(thickness 0.1524)
				)
			)
		)
		(property "Device Type" "R402H14"
			(at 0.064008 -5.517896 180)
			(unlocked yes)
			(layer "F.Fab")
			(hide yes)
			(effects
				(font
					(size 1.016 1.016)
					(thickness 0.1524)
				)
			)
		)
		(duplicate_pad_numbers_are_jumpers no)
		(fp_line
			(start 0.508 -0.9398)
			(end -0.508 -0.9398)
			(stroke
				(width 0.1524)
				(type default)
			)
			(layer "F.SilkS")
		)
		(fp_line
			(start -0.508 -0.9398)
			(end -0.508 0.9398)
			(stroke
				(width 0.1524)
				(type default)
			)
			(layer "F.SilkS")
		)
		(fp_rect
			(start -0.508 0.9398)
			(end 0.508 -0.9398)
			(stroke
				(width 0)
				(type default)
			)
			(fill no)
			(layer "F.CrtYd")
		)
		(fp_rect
			(start -0.508 0.9398)
			(end 0.508 -0.9398)
			(stroke
				(width 0)
				(type default)
			)
			(fill no)
			(layer "F.Fab")
		)
		(pad "1" smd custom
			(at 0 -0.4445 180)
			(size 0.1397 0.1397)
			(layers "F.Cu" "F.Mask" "F.Paste")
			(net "ADM1276_SENSE+")
			(options
				(clearance outline)
				(anchor circle)
			)
			(primitives
				(gr_poly
					(pts
						(arc
							(start -0.1778 -0.2794)
							(mid -0.249642 -0.249642)
							(end -0.2794 -0.1778)
						)
						(arc
							(start -0.2794 0.1778)
							(mid -0.249642 0.249642)
							(end -0.1778 0.2794)
						)
						(arc
							(start 0.1778 0.2794)
							(mid 0.249642 0.249642)
							(end 0.2794 0.1778)
						)
						(arc
							(start 0.2794 -0.1778)
							(mid 0.249642 -0.249642)
							(end 0.1778 -0.2794)
						)
					)
					(width 0)
					(fill yes)
				)
			)
		)
		(pad "2" smd custom
			(at 0 0.4445 180)
			(size 0.1397 0.1397)
			(layers "F.Cu" "F.Mask" "F.Paste")
			(net "SENSE+_R4")
			(options
				(clearance outline)
				(anchor circle)
			)
			(primitives
				(gr_poly
					(pts
						(arc
							(start -0.1778 -0.2794)
							(mid -0.249642 -0.249642)
							(end -0.2794 -0.1778)
						)
						(arc
							(start -0.2794 0.1778)
							(mid -0.249642 0.249642)
							(end -0.1778 0.2794)
						)
						(arc
							(start 0.1778 0.2794)
							(mid 0.249642 0.249642)
							(end 0.2794 0.1778)
						)
						(arc
							(start 0.2794 -0.1778)
							(mid 0.249642 -0.249642)
							(end 0.1778 -0.2794)
						)
					)
					(width 0)
					(fill yes)
				)
			)
		)
	)
	(footprint ""
		(layer "F.Cu")
		(at 12.9794 -449.5292 90)
		(property "Reference" "R105"
			(at 0 0 90)
			(layer "F.SilkS")
			(hide yes)
			(effects
				(font
					(size 1.27 1.27)
				)
			)
		)
		(property "Value" "10KR2F-2-GP"
			(at 0.064008 -3.993896 90)
			(unlocked yes)
			(layer "F.Fab")
			(hide yes)
			(effects
				(font
					(size 1.016 1.016)
					(thickness 0.1524)
				)
			)
		)
		(property "Device Type" "R402H16"
			(at 0.064008 -5.517896 90)
			(unlocked yes)
			(layer "F.Fab")
			(hide yes)
			(effects
				(font
					(size 1.016 1.016)
					(thickness 0.1524)
				)
			)
		)
		(duplicate_pad_numbers_are_jumpers no)
		(fp_line
			(start 0.508 -0.9398)
			(end -0.508 -0.9398)
			(stroke
				(width 0.1524)
				(type default)
			)
			(layer "F.SilkS")
		)
		(fp_line
			(start -0.508 -0.9398)
			(end -0.508 0.9398)
			(stroke
				(width 0.1524)
				(type default)
			)
			(layer "F.SilkS")
		)
		(fp_rect
			(start -0.508 0.9398)
			(end 0.508 -0.9398)
			(stroke
				(width 0)
				(type default)
			)
			(fill no)
			(layer "F.CrtYd")
		)
		(fp_rect
			(start -0.508 0.9398)
			(end 0.508 -0.9398)
			(stroke
				(width 0)
				(type default)
			)
			(fill no)
			(layer "F.Fab")
		)
		(pad "1" smd custom
			(at 0 -0.4445 90)
			(size 0.1397 0.1397)
			(layers "F.Cu" "F.Mask" "F.Paste")
			(net "FANIN_2")
			(options
				(clearance outline)
				(anchor circle)
			)
			(primitives
				(gr_poly
					(pts
						(arc
							(start -0.1778 -0.2794)
							(mid -0.249642 -0.249642)
							(end -0.2794 -0.1778)
						)
						(arc
							(start -0.2794 0.1778)
							(mid -0.249642 0.249642)
							(end -0.1778 0.2794)
						)
						(arc
							(start 0.1778 0.2794)
							(mid 0.249642 0.249642)
							(end 0.2794 0.1778)
						)
						(arc
							(start 0.2794 -0.1778)
							(mid 0.249642 -0.249642)
							(end 0.1778 -0.2794)
						)
					)
					(width 0)
					(fill yes)
				)
			)
		)
		(pad "2" smd custom
			(at 0 0.4445 90)
			(size 0.1397 0.1397)
			(layers "F.Cu" "F.Mask" "F.Paste")
			(net "GND")
			(options
				(clearance outline)
				(anchor circle)
			)
			(primitives
				(gr_poly
					(pts
						(arc
							(start -0.1778 -0.2794)
							(mid -0.249642 -0.249642)
							(end -0.2794 -0.1778)
						)
						(arc
							(start -0.2794 0.1778)
							(mid -0.249642 0.249642)
							(end -0.1778 0.2794)
						)
						(arc
							(start 0.1778 0.2794)
							(mid 0.249642 0.249642)
							(end 0.2794 0.1778)
						)
						(arc
							(start 0.2794 -0.1778)
							(mid 0.249642 -0.249642)
							(end 0.1778 -0.2794)
						)
					)
					(width 0)
					(fill yes)
				)
			)
		)
	)
)
